(kicad_pcb
	(version 20241229)
	(generator "pcbnew")
	(generator_version "9.0")
	(general
		(thickness 1.599998)
		(legacy_teardrops no)
	)
	(paper "A4")
	(title_block
		(title "Artix - Datacenter Secure Control Module (DC-SCM)")
		(date "2024-11-06")
		(rev "1.1.3")
		(comment 9 "footprints 62-67 of 544")
	)
	(layers
		(0 "F.Cu" signal)
		(4 "In1.Cu" signal)
		(6 "In2.Cu" signal)
		(8 "In3.Cu" signal)
		(10 "In4.Cu" signal)
		(12 "In5.Cu" signal)
		(14 "In6.Cu" signal)
		(2 "B.Cu" signal)
		(9 "F.Adhes" user "F.Adhesive")
		(11 "B.Adhes" user "B.Adhesive")
		(13 "F.Paste" user)
		(15 "B.Paste" user)
		(5 "F.SilkS" user "F.Silkscreen")
		(7 "B.SilkS" user "B.Silkscreen")
		(1 "F.Mask" user)
		(3 "B.Mask" user)
		(17 "Dwgs.User" user "User.Drawings")
		(19 "Cmts.User" user "User.Comments")
		(21 "Eco1.User" user "User.Eco1")
		(23 "Eco2.User" user "User.Eco2")
		(25 "Edge.Cuts" user)
		(27 "Margin" user)
		(31 "F.CrtYd" user "F.Courtyard")
		(29 "B.CrtYd" user "B.Courtyard")
		(35 "F.Fab" user)
		(33 "B.Fab" user)
	)
	(footprint "antmicro-footprints:C_0402_1005Metric"
		(layer "F.Cu")
		(at 100.175 157.475)
		(descr "Capacitor SMD 0402")
		(tags "capacitor SMD 0402")
		(property "Reference" "C1"
			(at -2.275 0.325 0)
			(layer "F.SilkS")
			(effects
				(font
					(size 0.7 0.7)
					(thickness 0.15)
				)
				(justify left bottom)
			)
		)
		(property "Value" "C_1n_0402"
			(at 0 1.4 0)
			(layer "F.Fab")
			(effects
				(font
					(size 0.7 0.7)
					(thickness 0.15)
				)
				(justify left bottom)
			)
		)
		(property "Datasheet" "https://www.murata.com/products/productdetail?partno=GRM1555C1H102JA01%23"
			(at 0 0 0)
			(layer "F.Fab")
			(hide yes)
			(effects
				(font
					(size 1.27 1.27)
					(thickness 0.15)
				)
			)
		)
		(property "Description" "SMD Multilayer Ceramic Capacitor, 1000 pF, 50 V, 0402 [1005 Metric], ± 5%, C0G / NP0, GRM Series"
			(at 0 0 0)
			(layer "F.Fab")
			(hide yes)
			(effects
				(font
					(size 1.27 1.27)
					(thickness 0.15)
				)
			)
		)
		(property "Author" "Antmicro"
			(at 0 0 0)
			(layer "F.Fab")
			(hide yes)
			(effects
				(font
					(size 1 1)
					(thickness 0.15)
				)
			)
		)
		(property "Dielectric" "C0G"
			(at 0 0 0)
			(layer "F.Fab")
			(hide yes)
			(effects
				(font
					(size 1 1)
					(thickness 0.15)
				)
			)
		)
		(property "License" "Apache-2.0"
			(at 0 0 0)
			(layer "F.Fab")
			(hide yes)
			(effects
				(font
					(size 1 1)
					(thickness 0.15)
				)
			)
		)
		(property "MPN" "GRM1555C1H102JA01D"
			(at 0 0 0)
			(layer "F.Fab")
			(hide yes)
			(effects
				(font
					(size 1 1)
					(thickness 0.15)
				)
			)
		)
		(property "Manufacturer" "Murata"
			(at 0 0 0)
			(layer "F.Fab")
			(hide yes)
			(effects
				(font
					(size 1 1)
					(thickness 0.15)
				)
			)
		)
		(property "Val" "1n"
			(at 0 0 0)
			(layer "F.Fab")
			(hide yes)
			(effects
				(font
					(size 1 1)
					(thickness 0.15)
				)
			)
		)
		(property "Voltage" "50V"
			(at 0 0 0)
			(layer "F.Fab")
			(hide yes)
			(effects
				(font
					(size 1 1)
					(thickness 0.15)
				)
			)
		)
		(sheetname "/DDR3/")
		(sheetfile "ddr3.kicad_sch")
		(attr smd)
		(fp_rect
			(start -0.925 -0.47)
			(end 0.925 0.47)
			(stroke
				(width 0.05)
				(type default)
			)
			(fill no)
			(layer "F.CrtYd")
		)
		(fp_line
			(start -0.494 -0.25)
			(end 0.504 -0.25)
			(stroke
				(width 0.15)
				(type solid)
			)
			(layer "F.Fab")
		)
		(fp_line
			(start -0.494 0.248)
			(end -0.494 -0.25)
			(stroke
				(width 0.15)
				(type solid)
			)
			(layer "F.Fab")
		)
		(fp_line
			(start 0.504 -0.25)
			(end 0.504 0.248)
			(stroke
				(width 0.15)
				(type solid)
			)
			(layer "F.Fab")
		)
		(fp_line
			(start 0.504 0.248)
			(end -0.494 0.248)
			(stroke
				(width 0.15)
				(type solid)
			)
			(layer "F.Fab")
		)
		(pad "1" smd roundrect
			(at -0.48 0)
			(size 0.59 0.64)
			(layers "F.Cu" "F.Mask" "F.Paste")
			(roundrect_rratio 0.25)
			(net 1 "GND")
			(pintype "passive")
		)
		(pad "2" smd roundrect
			(at 0.48 0)
			(size 0.59 0.64)
			(layers "F.Cu" "F.Mask" "F.Paste")
			(roundrect_rratio 0.25)
			(net 9 "Net-(U8-REFIN)")
			(pintype "passive")
		)
	)
	(footprint "antmicro-footprints:LED_0603_1608Metric_G"
		(layer "F.Cu")
		(at 67.466 86.265 180)
		(descr "LED SMD 0603 Green")
		(tags "LED SMD 0603 Green")
		(property "Reference" "D9"
			(at -2.834 -0.435 0)
			(layer "F.SilkS")
			(effects
				(font
					(size 0.7 0.7)
					(thickness 0.15)
				)
				(justify right bottom)
			)
		)
		(property "Value" "LED_G_0603_LG_L29K-G2J1-24-Z"
			(at 0 1.6 0)
			(layer "F.Fab")
			(effects
				(font
					(size 0.7 0.7)
					(thickness 0.15)
				)
				(justify right bottom)
			)
		)
		(property "Datasheet" "https://look.ams-osram.com/m/19ee86b3ae0ee95b/original/LG-L29K.pdf"
			(at 0 0 180)
			(layer "F.Fab")
			(hide yes)
			(effects
				(font
					(size 1.27 1.27)
					(thickness 0.15)
				)
			)
		)
		(property "Description" "LED, Green, SMD, 0603, 20 mA, 1.7 V, 570 nm"
			(at 0 0 180)
			(layer "F.Fab")
			(hide yes)
			(effects
				(font
					(size 1.27 1.27)
					(thickness 0.15)
				)
			)
		)
		(property "Author" "Antmicro"
			(at 134.932 172.53 0)
			(layer "F.Fab")
			(hide yes)
			(effects
				(font
					(size 1 1)
					(thickness 0.15)
				)
			)
		)
		(property "Color" "Green"
			(at 134.932 172.53 0)
			(layer "F.Fab")
			(hide yes)
			(effects
				(font
					(size 1 1)
					(thickness 0.15)
				)
			)
		)
		(property "License" "Apache-2.0"
			(at 134.932 172.53 0)
			(layer "F.Fab")
			(hide yes)
			(effects
				(font
					(size 1 1)
					(thickness 0.15)
				)
			)
		)
		(property "MPN" "LG L29K-G2J1-24-Z"
			(at 134.932 172.53 0)
			(layer "F.Fab")
			(hide yes)
			(effects
				(font
					(size 1 1)
					(thickness 0.15)
				)
			)
		)
		(property "Manufacturer" "OSRAM"
			(at 134.932 172.53 0)
			(layer "F.Fab")
			(hide yes)
			(effects
				(font
					(size 1 1)
					(thickness 0.15)
				)
			)
		)
		(sheetname "/FPGA banks 34-35 & CFG/")
		(sheetfile "fpga-banks-34-25-cfg.kicad_sch")
		(attr smd)
		(fp_line
			(start 0.22 0.35)
			(end -0.22 0.35)
			(stroke
				(width 0.15)
				(type solid)
			)
			(layer "F.SilkS")
		)
		(fp_line
			(start 0.22 -0.35)
			(end -0.22 -0.35)
			(stroke
				(width 0.15)
				(type solid)
			)
			(layer "F.SilkS")
		)
		(fp_line
			(start 0.105328 0.201008)
			(end 0.105328 -0.198992)
			(stroke
				(width 0.1)
				(type solid)
			)
			(layer "F.SilkS")
		)
		(fp_line
			(start 0.105328 0.201008)
			(end -0.094672 0.001008)
			(stroke
				(width 0.1)
				(type solid)
			)
			(layer "F.SilkS")
		)
		(fp_line
			(start 0.105328 0.001008)
			(end 0.24 0.001)
			(stroke
				(width 0.1)
				(type solid)
			)
			(layer "F.SilkS")
		)
		(fp_line
			(start -0.094672 0.201008)
			(end -0.094672 -0.198992)
			(stroke
				(width 0.1)
				(type solid)
			)
			(layer "F.SilkS")
		)
		(fp_line
			(start -0.094672 0.001008)
			(end 0.105328 -0.198992)
			(stroke
				(width 0.1)
				(type solid)
			)
			(layer "F.SilkS")
		)
		(fp_line
			(start -0.094672 0.001008)
			(end -0.24 0.001008)
			(stroke
				(width 0.1)
				(type solid)
			)
			(layer "F.SilkS")
		)
		(fp_line
			(start -1.18 -0.319)
			(end -1.18 0.321)
			(stroke
				(width 0.15)
				(type solid)
			)
			(layer "F.SilkS")
		)
		(fp_rect
			(start 1.25 0.65)
			(end -1.25 -0.65)
			(stroke
				(width 0.05)
				(type solid)
			)
			(fill no)
			(layer "F.CrtYd")
		)
		(fp_line
			(start 0.599 0)
			(end 0.201 0)
			(stroke
				(width 0.15)
				(type solid)
			)
			(layer "F.Fab")
		)
		(fp_line
			(start 0.201 0.2)
			(end 0.201 0)
			(stroke
				(width 0.15)
				(type solid)
			)
			(layer "F.Fab")
		)
		(fp_line
			(start 0.201 0)
			(end 0.201 -0.202)
			(stroke
				(width 0.15)
				(type solid)
			)
			(layer "F.Fab")
		)
		(fp_line
			(start 0.201 -0.202)
			(end -0.101 0)
			(stroke
				(width 0.15)
				(type solid)
			)
			(layer "F.Fab")
		)
		(fp_line
			(start -0.101 0)
			(end 0.201 0.2)
			(stroke
				(width 0.15)
				(type solid)
			)
			(layer "F.Fab")
		)
		(fp_line
			(start -0.199 0.2)
			(end -0.199 0.1)
			(stroke
				(width 0.15)
				(type solid)
			)
			(layer "F.Fab")
		)
		(fp_line
			(start -0.199 0)
			(end -0.597 0)
			(stroke
				(width 0.15)
				(type solid)
			)
			(layer "F.Fab")
		)
		(fp_line
			(start -0.199 -0.202)
			(end -0.199 0.1)
			(stroke
				(width 0.15)
				(type solid)
			)
			(layer "F.Fab")
		)
		(fp_rect
			(start 0.848 0.4)
			(end -0.85 -0.402)
			(stroke
				(width 0.15)
				(type solid)
			)
			(fill no)
			(layer "F.Fab")
		)
		(pad "1" smd roundrect
			(at -0.7 0)
			(size 0.8 1)
			(layers "F.Cu" "F.Mask" "F.Paste")
			(roundrect_rratio 0.2)
			(net 225 "Net-(D9-C)")
			(pinfunction "C")
			(pintype "passive")
		)
		(pad "2" smd roundrect
			(at 0.7 0)
			(size 0.8 1)
			(layers "F.Cu" "F.Mask" "F.Paste")
			(roundrect_rratio 0.2)
			(net 279 "Net-(D9-A)")
			(pinfunction "A")
			(pintype "passive")
		)
	)
	(footprint "antmicro-footprints:R_0402_1005Metric"
		(layer "F.Cu")
		(at 74.74 162.06 -90)
		(descr "Resistor SMD 0402")
		(tags "resistor SMD 0402")
		(property "Reference" "R45"
			(at -2.16 -8.36 90)
			(layer "F.SilkS")
			(effects
				(font
					(size 0.7 0.7)
					(thickness 0.15)
				)
				(justify right bottom)
			)
		)
		(property "Value" "R_357k_0402"
			(at 0 1.4 90)
			(layer "F.Fab")
			(effects
				(font
					(size 0.7 0.7)
					(thickness 0.15)
				)
				(justify right bottom)
			)
		)
		(property "Datasheet" "https://www.bourns.com/docs/product-datasheets/cr.pdf"
			(at 0 0 270)
			(layer "F.Fab")
			(hide yes)
			(effects
				(font
					(size 1.27 1.27)
					(thickness 0.15)
				)
			)
		)
		(property "Description" "SMD Chip Resistor"
			(at 0 0 270)
			(layer "F.Fab")
			(hide yes)
			(effects
				(font
					(size 1.27 1.27)
					(thickness 0.15)
				)
			)
		)
		(property "Author" "Antmicro"
			(at -87.32 236.8 0)
			(layer "F.Fab")
			(hide yes)
			(effects
				(font
					(size 1 1)
					(thickness 0.15)
				)
			)
		)
		(property "License" "Apache-2.0"
			(at -87.32 236.8 0)
			(layer "F.Fab")
			(hide yes)
			(effects
				(font
					(size 1 1)
					(thickness 0.15)
				)
			)
		)
		(property "MPN" "CR0402-FX-3573GLF"
			(at -87.32 236.8 0)
			(layer "F.Fab")
			(hide yes)
			(effects
				(font
					(size 1 1)
					(thickness 0.15)
				)
			)
		)
		(property "Manufacturer" "Bourns"
			(at -87.32 236.8 0)
			(layer "F.Fab")
			(hide yes)
			(effects
				(font
					(size 1 1)
					(thickness 0.15)
				)
			)
		)
		(property "Tolerance" "1%"
			(at -87.32 236.8 0)
			(layer "F.Fab")
			(hide yes)
			(effects
				(font
					(size 1 1)
					(thickness 0.15)
				)
			)
		)
		(property "Val" "357k"
			(at -87.32 236.8 0)
			(layer "F.Fab")
			(hide yes)
			(effects
				(font
					(size 1 1)
					(thickness 0.15)
				)
			)
		)
		(sheetname "/Interfaces/")
		(sheetfile "interfaces.kicad_sch")
		(attr smd)
		(fp_rect
			(start -0.925 -0.47)
			(end 0.925 0.47)
			(stroke
				(width 0.05)
				(type default)
			)
			(fill no)
			(layer "F.CrtYd")
		)
		(fp_rect
			(start -0.5 -0.25)
			(end 0.5 0.25)
			(stroke
				(width 0.15)
				(type solid)
			)
			(fill no)
			(layer "F.Fab")
		)
		(pad "1" smd roundrect
			(at -0.48 0 270)
			(size 0.59 0.64)
			(layers "F.Cu" "F.Mask" "F.Paste")
			(roundrect_rratio 0.25)
			(net 2 "VCC3V3")
			(pintype "passive")
		)
		(pad "2" smd roundrect
			(at 0.48 0 270)
			(size 0.59 0.64)
			(layers "F.Cu" "F.Mask" "F.Paste")
			(roundrect_rratio 0.25)
			(net 168 "I3C[0]_SDA_3V3")
			(pintype "passive")
		)
	)
	(footprint "antmicro-footprints:R_0402_1005Metric"
		(layer "F.Cu")
		(at 73.74 162.06 -90)
		(descr "Resistor SMD 0402")
		(tags "resistor SMD 0402")
		(property "Reference" "R46"
			(at -2.16 -8.36 90)
			(layer "F.SilkS")
			(effects
				(font
					(size 0.7 0.7)
					(thickness 0.15)
				)
				(justify right bottom)
			)
		)
		(property "Value" "R_357k_0402"
			(at 0 1.4 90)
			(layer "F.Fab")
			(effects
				(font
					(size 0.7 0.7)
					(thickness 0.15)
				)
				(justify right bottom)
			)
		)
		(property "Datasheet" "https://www.bourns.com/docs/product-datasheets/cr.pdf"
			(at 0 0 270)
			(layer "F.Fab")
			(hide yes)
			(effects
				(font
					(size 1.27 1.27)
					(thickness 0.15)
				)
			)
		)
		(property "Description" "SMD Chip Resistor"
			(at 0 0 270)
			(layer "F.Fab")
			(hide yes)
			(effects
				(font
					(size 1.27 1.27)
					(thickness 0.15)
				)
			)
		)
		(property "Author" "Antmicro"
			(at -88.32 235.8 0)
			(layer "F.Fab")
			(hide yes)
			(effects
				(font
					(size 1 1)
					(thickness 0.15)
				)
			)
		)
		(property "License" "Apache-2.0"
			(at -88.32 235.8 0)
			(layer "F.Fab")
			(hide yes)
			(effects
				(font
					(size 1 1)
					(thickness 0.15)
				)
			)
		)
		(property "MPN" "CR0402-FX-3573GLF"
			(at -88.32 235.8 0)
			(layer "F.Fab")
			(hide yes)
			(effects
				(font
					(size 1 1)
					(thickness 0.15)
				)
			)
		)
		(property "Manufacturer" "Bourns"
			(at -88.32 235.8 0)
			(layer "F.Fab")
			(hide yes)
			(effects
				(font
					(size 1 1)
					(thickness 0.15)
				)
			)
		)
		(property "Tolerance" "1%"
			(at -88.32 235.8 0)
			(layer "F.Fab")
			(hide yes)
			(effects
				(font
					(size 1 1)
					(thickness 0.15)
				)
			)
		)
		(property "Val" "357k"
			(at -88.32 235.8 0)
			(layer "F.Fab")
			(hide yes)
			(effects
				(font
					(size 1 1)
					(thickness 0.15)
				)
			)
		)
		(sheetname "/Interfaces/")
		(sheetfile "interfaces.kicad_sch")
		(attr smd)
		(fp_rect
			(start -0.925 -0.47)
			(end 0.925 0.47)
			(stroke
				(width 0.05)
				(type default)
			)
			(fill no)
			(layer "F.CrtYd")
		)
		(fp_rect
			(start -0.5 -0.25)
			(end 0.5 0.25)
			(stroke
				(width 0.15)
				(type solid)
			)
			(fill no)
			(layer "F.Fab")
		)
		(pad "1" smd roundrect
			(at -0.48 0 270)
			(size 0.59 0.64)
			(layers "F.Cu" "F.Mask" "F.Paste")
			(roundrect_rratio 0.25)
			(net 2 "VCC3V3")
			(pintype "passive")
		)
		(pad "2" smd roundrect
			(at 0.48 0 270)
			(size 0.59 0.64)
			(layers "F.Cu" "F.Mask" "F.Paste")
			(roundrect_rratio 0.25)
			(net 169 "I3C[0]_SCL_3V3")
			(pintype "passive")
		)
	)
	(footprint "antmicro-footprints:R_0402_1005Metric"
		(layer "F.Cu")
		(at 78.74 162.06 -90)
		(descr "Resistor SMD 0402")
		(tags "resistor SMD 0402")
		(property "Reference" "R49"
			(at -2.16 -8.36 90)
			(layer "F.SilkS")
			(effects
				(font
					(size 0.7 0.7)
					(thickness 0.15)
				)
				(justify right bottom)
			)
		)
		(property "Value" "R_357k_0402"
			(at 0 1.4 90)
			(layer "F.Fab")
			(effects
				(font
					(size 0.7 0.7)
					(thickness 0.15)
				)
				(justify right bottom)
			)
		)
		(property "Datasheet" "https://www.bourns.com/docs/product-datasheets/cr.pdf"
			(at 0 0 270)
			(layer "F.Fab")
			(hide yes)
			(effects
				(font
					(size 1.27 1.27)
					(thickness 0.15)
				)
			)
		)
		(property "Description" "SMD Chip Resistor"
			(at 0 0 270)
			(layer "F.Fab")
			(hide yes)
			(effects
				(font
					(size 1.27 1.27)
					(thickness 0.15)
				)
			)
		)
		(property "Author" "Antmicro"
			(at -83.32 240.8 0)
			(layer "F.Fab")
			(hide yes)
			(effects
				(font
					(size 1 1)
					(thickness 0.15)
				)
			)
		)
		(property "License" "Apache-2.0"
			(at -83.32 240.8 0)
			(layer "F.Fab")
			(hide yes)
			(effects
				(font
					(size 1 1)
					(thickness 0.15)
				)
			)
		)
		(property "MPN" "CR0402-FX-3573GLF"
			(at -83.32 240.8 0)
			(layer "F.Fab")
			(hide yes)
			(effects
				(font
					(size 1 1)
					(thickness 0.15)
				)
			)
		)
		(property "Manufacturer" "Bourns"
			(at -83.32 240.8 0)
			(layer "F.Fab")
			(hide yes)
			(effects
				(font
					(size 1 1)
					(thickness 0.15)
				)
			)
		)
		(property "Tolerance" "1%"
			(at -83.32 240.8 0)
			(layer "F.Fab")
			(hide yes)
			(effects
				(font
					(size 1 1)
					(thickness 0.15)
				)
			)
		)
		(property "Val" "357k"
			(at -83.32 240.8 0)
			(layer "F.Fab")
			(hide yes)
			(effects
				(font
					(size 1 1)
					(thickness 0.15)
				)
			)
		)
		(sheetname "/Interfaces/")
		(sheetfile "interfaces.kicad_sch")
		(attr smd)
		(fp_rect
			(start -0.925 -0.47)
			(end 0.925 0.47)
			(stroke
				(width 0.05)
				(type default)
			)
			(fill no)
			(layer "F.CrtYd")
		)
		(fp_rect
			(start -0.5 -0.25)
			(end 0.5 0.25)
			(stroke
				(width 0.15)
				(type solid)
			)
			(fill no)
			(layer "F.Fab")
		)
		(pad "1" smd roundrect
			(at -0.48 0 270)
			(size 0.59 0.64)
			(layers "F.Cu" "F.Mask" "F.Paste")
			(roundrect_rratio 0.25)
			(net 2 "VCC3V3")
			(pintype "passive")
		)
		(pad "2" smd roundrect
			(at 0.48 0 270)
			(size 0.59 0.64)
			(layers "F.Cu" "F.Mask" "F.Paste")
			(roundrect_rratio 0.25)
			(net 172 "I3C[2]_SDA_3V3")
			(pintype "passive")
		)
	)
	(footprint "antmicro-footprints:R_0402_1005Metric"
		(layer "F.Cu")
		(at 77.74 162.06 -90)
		(descr "Resistor SMD 0402")
		(tags "resistor SMD 0402")
		(property "Reference" "R50"
			(at -2.16 -8.36 90)
			(layer "F.SilkS")
			(effects
				(font
					(size 0.7 0.7)
					(thickness 0.15)
				)
				(justify right bottom)
			)
		)
		(property "Value" "R_357k_0402"
			(at 0 1.4 90)
			(layer "F.Fab")
			(effects
				(font
					(size 0.7 0.7)
					(thickness 0.15)
				)
				(justify right bottom)
			)
		)
		(property "Datasheet" "https://www.bourns.com/docs/product-datasheets/cr.pdf"
			(at 0 0 270)
			(layer "F.Fab")
			(hide yes)
			(effects
				(font
					(size 1.27 1.27)
					(thickness 0.15)
				)
			)
		)
		(property "Description" "SMD Chip Resistor"
			(at 0 0 270)
			(layer "F.Fab")
			(hide yes)
			(effects
				(font
					(size 1.27 1.27)
					(thickness 0.15)
				)
			)
		)
		(property "Author" "Antmicro"
			(at -84.32 239.8 0)
			(layer "F.Fab")
			(hide yes)
			(effects
				(font
					(size 1 1)
					(thickness 0.15)
				)
			)
		)
		(property "License" "Apache-2.0"
			(at -84.32 239.8 0)
			(layer "F.Fab")
			(hide yes)
			(effects
				(font
					(size 1 1)
					(thickness 0.15)
				)
			)
		)
		(property "MPN" "CR0402-FX-3573GLF"
			(at -84.32 239.8 0)
			(layer "F.Fab")
			(hide yes)
			(effects
				(font
					(size 1 1)
					(thickness 0.15)
				)
			)
		)
		(property "Manufacturer" "Bourns"
			(at -84.32 239.8 0)
			(layer "F.Fab")
			(hide yes)
			(effects
				(font
					(size 1 1)
					(thickness 0.15)
				)
			)
		)
		(property "Tolerance" "1%"
			(at -84.32 239.8 0)
			(layer "F.Fab")
			(hide yes)
			(effects
				(font
					(size 1 1)
					(thickness 0.15)
				)
			)
		)
		(property "Val" "357k"
			(at -84.32 239.8 0)
			(layer "F.Fab")
			(hide yes)
			(effects
				(font
					(size 1 1)
					(thickness 0.15)
				)
			)
		)
		(sheetname "/Interfaces/")
		(sheetfile "interfaces.kicad_sch")
		(attr smd)
		(fp_rect
			(start -0.925 -0.47)
			(end 0.925 0.47)
			(stroke
				(width 0.05)
				(type default)
			)
			(fill no)
			(layer "F.CrtYd")
		)
		(fp_rect
			(start -0.5 -0.25)
			(end 0.5 0.25)
			(stroke
				(width 0.15)
				(type solid)
			)
			(fill no)
			(layer "F.Fab")
		)
		(pad "1" smd roundrect
			(at -0.48 0 270)
			(size 0.59 0.64)
			(layers "F.Cu" "F.Mask" "F.Paste")
			(roundrect_rratio 0.25)
			(net 2 "VCC3V3")
			(pintype "passive")
		)
		(pad "2" smd roundrect
			(at 0.48 0 270)
			(size 0.59 0.64)
			(layers "F.Cu" "F.Mask" "F.Paste")
			(roundrect_rratio 0.25)
			(net 173 "I3C[2]_SCL_3V3")
			(pintype "passive")
		)
	)
)
